# S9S_MB_2U (Grand Teton) — schematic netlist excerpt (pin names and nets, part order shuffled) for the footprints in the layout excerpt that follows; sources: Cadence DE-HDL packaged netlist, KiCad conversion of 03242023_DA0F0TMBIJ0_F0T_Motherboard_J_brd_V01_OCP.brd

J41  SCONN168_ME1016810202011  IO  pkg CON_F168S2H7D_P0-6W2-95_LUH  page 240
  GND_A1  = SMB_OCP_SFF_3V3AUX_SCL_R0
  GND_A2  = SMB_OCP_SFF_3V3AUX_SDA_R0
  GND_A3  = SMB_HOST_3V3AUX_SCL_R0
  GND_A4  = SMB_HOST_3V3AUX_SDA_R0
  GND_A5  = SMB_VR_3V3AUX_SCL_R0
  GND_A6  = SMB_VR_3V3AUX_SDA_R0
  SMCLK  = SMB_SML1_PMBUS_3V3AUX_PCH_SCL_R
  SMDAT  = SMB_SML1_PMBUS_3V3AUX_PCH_SDA_R
  \smrst#\  = I3C_BMC_SWB_SCL
  \prsnta#\  = I3C_BMC_SWB_SDA
  \perst1#\  = SMB_OCP_V3_2_3V3AUX_SCL_R0
  \prsntb2#\  = SMB_OCP_V3_2_3V3AUX_SDA_R0
  GND_A13  = GND
  REFCLKN1  = CLK_100M_BMC_P3E_DP_R
  REFCLKP1  = CLK_100M_BMC_P3E_DN_R
  GND_A16  = GND
  PERN0  = P3E_PCH_BMC_TX_C_DP
  PERP0  = P3E_PCH_BMC_TX_C_DN
  GND_A19  = GND
  PERN1  = P3E_PCH_BMC_RX_DP
  PERP1  = P3E_PCH_BMC_RX_DN
  GND_A22  = GND
  PERN2  = SMB_PCIE0_3V3AUX_SCL
  PERP2  = SMB_PCIE0_3V3AUX_SDA
  GND_A25  = SMB_SML0_3V3AUX_SCL_R1
  PERN3  = SMB_SML0_3V3AUX_SDA_R1
  PERP3  = SMB_1_PLD_3V3AUX_SCL_R3
  GND_A28  = SMB_1_PLD_3V3AUX_SDA_R3
  GND_A29  = SMB_FAN_3V3AUX_SCL
  PERN4  = SMB_FAN_3V3AUX_SDA
  PERP4  = SMB_PCIE2_3V3AUX_SCL_R0
  GND_A32  = SMB_PCIE2_3V3AUX_SDA_R0
  PERN5  = GND
  PERP5  = JTAG_BMC_TCK
  GND_A35  = JTAG_BMC_TMS
  PERN6  = JTAG_BMC_TDI
  PERP6  = JTAG_BMC_TDO
  GND_A38  = SMB_PCIE3_3V3AUX_SCL_R
  PERN7  = SMB_PCIE3_3V3AUX_SDA_R
  PERP7  = SMB_S3M_CPU_3V3AUX_SCL_R0
  GND_A41  = SMB_S3M_CPU_3V3AUX_SDA_R0
  \prsntb1#\  = GND
  GND_A43  = FM_JTAG_BMC_MUX_SEL_FROM_BMC_R2
  PERN8  = PWRGD_PS_PWROK_R
  PERP8  = TP_HPM_STBY_EN
  GND_A46  = RST_MB_STBY_N
  PERN9  = FM_BMC_PWRBTN_OUT_R_N
  PERP9  = PWRGD_SYS_PWROK
  GND_A49  = JTAG_BMC_DBP_PREQ_N
  PERN10  = JTAG_DBP_BMC_PRDY_N
  PERP10  = RST_PLTRST_B_N
  GND_A52  = FM_UARTSW_MSB_R
  PERN11  = ROT_P1_RST_IND_N
  PERP11  = FM_BMC_INTRUDER_N
  GND_A55  = FM_UARTSW_LSB_R
  PERN12  = IRQ0_A57
  PERP12  = FM_SCM_PRSNT1_N
  GND_A58  = GND
  PERN13  = USB3_PCH_RX_DP<4>
  PERP13  = USB3_PCH_RX_DN<4>
  GND_A61  = GND
  PERN14  = TP_PCIE_HPM_RXP<1>
  PERP14  = TP_PCIE_HPM_RXN<1>
  GND_A64  = GND
  PERN15  = P2E_MB_BMC_RX_BUF_DP<0>
  PERP15  = P2E_MB_BMC_RX_BUF_DN<0>
  GND_A67  = GND
  USB_DATN  = CLK_100M_BMC_RC_DP
  USB_DATP  = CLK_100M_BMC_RC_DN
  \pwrbrk0#\  = GND
  \+12v_edge_b1\  = ESPI_HOST_LPC_BMC_CLK
  \+12v_edge_b2\  = ESPI_HOST_LPC_BMC_LFRAME_N
  \+12v_edge_b3\  = IRQ_ESPI_LPC_SERIRQ_ALERT_R_N
  \+12v_edge_b4\  = ESPI_BMC_LPC_RST_N
  \+12v_edge_b5\  = ESPI_LPC_LAD0_IO0
  \+12v_edge_b6\  = ESPI_LPC_LAD0_IO1
  \bif0#\  = ESPI_LPC_LAD0_IO2
  \bif1#\  = ESPI_LPC_LAD0_IO3
  \bif2#\  = FM_LPC_ESPI_SEL
  \perst0#\  = GND
  \+3.3v_edge\  = SPI_SYS_CLK
  AUX_PWR_EN  = SPI_SYS_CS0_N
  GND_B13  = SPI_SYS_MOSI
  REFCLKN0  = SPI_SYS_MISO
  REFCLKP0  = SPI_SYS_WP_IO2
  GND_B16  = SPI_SYS_HOLD_IO3
  PETN0  = GND
  PETP0  = CLK_50M_RMII_BMC_OCP
  GND_B19  = RMII_OCP_BMC_CRSDV
  PETN1  = RMII_BMC_OCP_TX_EN
  PETP1  = RMII_BMC_OCP_TXD_0
  GND_B22  = RMII_BMC_OCP_TXD_1
  PETN2  = RMII_BMC_OCP_RX_ER
  PETP2  = RMII_OCP_BMC_RXD_0
  GND_B25  = RMII_OCP_BMC_RXD_1
  PETN3  = GND
  PETP3  = PECI_BMC
  GND_B28  = PVCCIO_PECI_BMC
  GND_B29  = SGPIO_DO_0
  PETN4  = SGPIO_CLK_0
  PETP4  = SGPIO_DI_0
  GND_B32  = SGPIO_LD_0
  PETN5  = GND
  PETP5  = SGPIO_DO_1
  GND_B35  = SGPIO_CLK_1
  PETN6  = SGPIO_DI_1
  PETP6  = SGPIO_LD_1
  GND_B38  = GND
  PETN7  = RST_SGPIO_RESET_N
  PETP7  = IRQ_SGPIO_INTR_N
  GND_B41  = P3V_BAT_R1
  \prsntb0#\  = FM_AC_PWR_BTN_N
  GND_B43  = TP_SPI_2_PLD_CLK
  PETN8  = TP_SPI_2_PLD_CS_N
  PETP8  = TP_SPI_2_PLD_IO0
  GND_B46  = TP_SPI_2_PLD_IO1
  PETN9  = TP_SPI_2_PLD_IO2
  PETP9  = TP_SPI_2_PLD_IO3
  GND_B49  = GND
  PETN10  = USB2_HOST_BMC_B_DP
  PETP10  = USB2_HOST_BMC_B_DN
  GND_B52  = GND
  PETN11  = USB2_8_DP
  PETP11  = USB2_8_DN
  GND_B55  = GND
  PETN12  = USB2_HUB_2_BUF_EXT_DP
  PETP12  = USB2_HUB_2_BUF_EXT_DN
  GND_B58  = GND
  PETN13  = USB3_PCH_TX_BUF_C_DP<4>
  PETP13  = USB3_PCH_TX_BUF_C_DN<4>
  GND_B61  = GND
  PETN14  = TP_PCIE_HPM_TXP<1>
  PETP14  = TP_PCIE_HPM_TXN<1>
  GND_B64  = GND
  PETN15  = P2E_MB_BMC_TX_C_DP<0>
  PETP15  = P2E_MB_BMC_TX_C_DN<0>
  GND_B67  = GND
  RFU1_NC_B68  = TP_PCIE_HPM_TXP<3>
  RFU1_NC_B69  = TP_PCIE_HPM_TXN<3>
  \prsntb3#\  = GND
  G1  = GND
  G2  = GND
  G3  = GND
  G4  = GND
  G5  = GND
  \perst2#\  = P12V_SCM
  \perst3#\  = P12V_SCM
  \wake#\  = GND
  RBT_ARB_IN  = GND
  RBT_ARB_OUT  = I3C_SPD_DDRABCD_CPU0_BMC_R_SCL
  SLOT_ID1  = I3C_SPD_DDRABCD_CPU0_BMC_R_SDA
  RBT_TX_EN  = I3C_SPD_DDREFGH_CPU0_BMC_R_SCL
  RBT_TXD1  = I3C_SPD_DDREFGH_CPU0_BMC_R_SDA
  RBT_TXD0  = I3C_SPD_DDRABCD_CPU1_BMC_R_SCL
  GND_OA10  = I3C_SPD_DDRABCD_CPU1_BMC_R_SDA
  REFCLKN3  = I3C_SPD_DDREFGH_CPU1_BMC_R_SCL
  REFCLKP3  = I3C_SPD_DDREFGH_CPU1_BMC_R_SDA
  GND_OA13  = GND
  RBT_CLK_IN  = VIRTUAL_RESEAT
  NIC_PWR_GOOD  = P12V_SCM
  MAIN_PWR_EN  = P12V_SCM
  \ld#\  = PRSNT0_N
  DATA_IN  = GND
  DATA_OUT  = UART_BMC_BIC_TX
  CLK  = UART_BMC_BIC_BUF_RX
  SLOT_ID0  = GND
  RBT_RXD1  = USB2_7_R_DP
  RBT_RXD0  = USB2_7_R_DN
  GND_OB10  = GND
  REFCLKN2  = RST_SRST_PLD_BMC_N
  REFCLKP2  = SPI_TPM_CS_N
  GND_OB13  = H_CPU_CATERR_LVC2_BMC_N
  RBT_CRS_DV  = FM_SOL_UART_CH_SEL_R

(kicad_pcb
	(version 20260206)
	(generator "pcbnew")
	(generator_version "10.0")
	(general
		(thickness 1.6)
		(legacy_teardrops no)
	)
	(paper "A4")
	(title_block
		(title "03242023_DA0F0TMBIJ0_F0T_Motherboard_J_brd_V01_OCP.brd")
		(comment 1 "Grand Teton / footprint 3077 of 6105 (J41), pads 87-131 of 175")
	)
	(layers
		(0 "F.Cu" signal "TOP")
		(4 "In1.Cu" signal "GND")
		(6 "In2.Cu" signal "IN1")
		(8 "In3.Cu" signal "GND1")
		(10 "In4.Cu" signal "IN2")
		(12 "In5.Cu" signal "GND2")
		(14 "In6.Cu" signal "IN3")
		(16 "In7.Cu" signal "GND3")
		(18 "In8.Cu" signal "VCC")
		(20 "In9.Cu" signal "VCC1")
		(22 "In10.Cu" signal "GND4")
		(24 "In11.Cu" signal "IN4")
		(26 "In12.Cu" signal "GND5")
		(28 "In13.Cu" signal "IN5")
		(30 "In14.Cu" signal "GND6")
		(32 "In15.Cu" signal "IN6")
		(34 "In16.Cu" signal "GND7")
		(2 "B.Cu" signal "BOTTOM")
		(9 "F.Adhes" user "F.Adhesive")
		(11 "B.Adhes" user "B.Adhesive")
		(13 "F.Paste" user "Package Geometry/Pastemask Top")
		(15 "B.Paste" user "Package Geometry/Pastemask Bottom")
		(5 "F.SilkS" user "Ref Des/Silkscreen Top")
		(7 "B.SilkS" user "Ref Des/Silkscreen Bottom")
		(1 "F.Mask" user "Board Geometry/Soldermask Top")
		(3 "B.Mask" user "Board Geometry/Soldermask Bottom")
		(17 "Dwgs.User" user "User.Drawings")
		(19 "Cmts.User" user "User.Comments")
		(21 "Eco1.User" user "User.Eco1")
		(23 "Eco2.User" user "User.Eco2")
		(25 "Edge.Cuts" user "Board Geometry/Outline")
		(27 "Margin" user)
		(31 "F.CrtYd" user "Package Geometry/Place Bound Top")
		(29 "B.CrtYd" user "Package Geometry/Place Bound Bottom")
		(35 "F.Fab" user "Ref Des/Assembly Top")
		(33 "B.Fab" user "Ref Des/Assembly Bottom")
	)
	(footprint ""
		(layer "F.Cu")
		(at 160.402016 -10.850118 -90)
		(property "Reference" "J41"
			(at -12.075414 24.511762 0)
			(unlocked yes)
			(layer "F.SilkS")
			(effects
				(font
					(size 0.7874 0.5842)
					(thickness 0.1524)
				)
				(justify left)
			)
		)
		(property "Value" ""
			(at 0 0 270)
			(layer "F.Fab")
			(effects
				(font
					(size 1.27 1.27)
				)
			)
		)
		(duplicate_pad_numbers_are_jumpers no)
		(pad "B15" smd rect
			(at -5.700014 -10.065004 180)
			(size 0.381 1.4478)
			(layers "F.Cu" "F.Mask" "F.Paste")
			(net "SPI_SYS_WP_IO2")
		)
		(pad "B16" smd rect
			(at -5.700014 -9.465056 180)
			(size 0.381 1.4478)
			(layers "F.Cu" "F.Mask" "F.Paste")
			(net "SPI_SYS_HOLD_IO3")
		)
		(pad "B17" smd rect
			(at -5.700014 -8.865108 180)
			(size 0.381 1.4478)
			(layers "F.Cu" "F.Mask" "F.Paste")
			(net "GND")
		)
		(pad "B18" smd rect
			(at -5.700014 -8.264906 180)
			(size 0.381 1.4478)
			(layers "F.Cu" "F.Mask" "F.Paste")
			(net "CLK_50M_RMII_BMC_OCP")
		)
		(pad "B19" smd rect
			(at -5.700014 -7.664958 180)
			(size 0.381 1.4478)
			(layers "F.Cu" "F.Mask" "F.Paste")
			(net "RMII_OCP_BMC_CRSDV")
		)
		(pad "B20" smd rect
			(at -5.700014 -7.06501 180)
			(size 0.381 1.4478)
			(layers "F.Cu" "F.Mask" "F.Paste")
			(net "RMII_BMC_OCP_TX_EN")
		)
		(pad "B21" smd rect
			(at -5.700014 -6.465062 180)
			(size 0.381 1.4478)
			(layers "F.Cu" "F.Mask" "F.Paste")
			(net "RMII_BMC_OCP_TXD_0")
		)
		(pad "B22" smd rect
			(at -5.700014 -5.865114 180)
			(size 0.381 1.4478)
			(layers "F.Cu" "F.Mask" "F.Paste")
			(net "RMII_BMC_OCP_TXD_1")
		)
		(pad "B23" smd rect
			(at -5.700014 -5.264912 180)
			(size 0.381 1.4478)
			(layers "F.Cu" "F.Mask" "F.Paste")
			(net "RMII_BMC_OCP_RX_ER")
		)
		(pad "B24" smd rect
			(at -5.700014 -4.664964 180)
			(size 0.381 1.4478)
			(layers "F.Cu" "F.Mask" "F.Paste")
			(net "RMII_OCP_BMC_RXD_0")
		)
		(pad "B25" smd rect
			(at -5.700014 -4.065016 180)
			(size 0.381 1.4478)
			(layers "F.Cu" "F.Mask" "F.Paste")
			(net "RMII_OCP_BMC_RXD_1")
		)
		(pad "B26" smd rect
			(at -5.700014 -3.465068 180)
			(size 0.381 1.4478)
			(layers "F.Cu" "F.Mask" "F.Paste")
			(net "GND")
		)
		(pad "B27" smd rect
			(at -5.700014 -2.86512 180)
			(size 0.381 1.4478)
			(layers "F.Cu" "F.Mask" "F.Paste")
			(net "PECI_BMC")
		)
		(pad "B28" smd rect
			(at -5.700014 -2.264918 180)
			(size 0.381 1.4478)
			(layers "F.Cu" "F.Mask" "F.Paste")
			(net "PVCCIO_PECI_BMC")
		)
		(pad "B29" smd rect
			(at -5.700014 1.74498 180)
			(size 0.381 1.4478)
			(layers "F.Cu" "F.Mask" "F.Paste")
			(net "SGPIO_DO_0")
		)
		(pad "B30" smd rect
			(at -5.700014 2.344928 180)
			(size 0.381 1.4478)
			(layers "F.Cu" "F.Mask" "F.Paste")
			(net "SGPIO_CLK_0")
		)
		(pad "B31" smd rect
			(at -5.700014 2.944876 180)
			(size 0.381 1.4478)
			(layers "F.Cu" "F.Mask" "F.Paste")
			(net "SGPIO_DI_0")
		)
		(pad "B32" smd rect
			(at -5.700014 3.545078 180)
			(size 0.381 1.4478)
			(layers "F.Cu" "F.Mask" "F.Paste")
			(net "SGPIO_LD_0")
		)
		(pad "B33" smd rect
			(at -5.700014 4.145026 180)
			(size 0.381 1.4478)
			(layers "F.Cu" "F.Mask" "F.Paste")
			(net "GND")
		)
		(pad "B34" smd rect
			(at -5.700014 4.744974 180)
			(size 0.381 1.4478)
			(layers "F.Cu" "F.Mask" "F.Paste")
			(net "SGPIO_DO_1")
		)
		(pad "B35" smd rect
			(at -5.700014 5.344922 180)
			(size 0.381 1.4478)
			(layers "F.Cu" "F.Mask" "F.Paste")
			(net "SGPIO_CLK_1")
		)
		(pad "B36" smd rect
			(at -5.700014 5.945124 180)
			(size 0.381 1.4478)
			(layers "F.Cu" "F.Mask" "F.Paste")
			(net "SGPIO_DI_1")
		)
		(pad "B37" smd rect
			(at -5.700014 6.545072 180)
			(size 0.381 1.4478)
			(layers "F.Cu" "F.Mask" "F.Paste")
			(net "SGPIO_LD_1")
		)
		(pad "B38" smd rect
			(at -5.700014 7.14502 180)
			(size 0.381 1.4478)
			(layers "F.Cu" "F.Mask" "F.Paste")
			(net "GND")
		)
		(pad "B39" smd rect
			(at -5.700014 7.744968 180)
			(size 0.381 1.4478)
			(layers "F.Cu" "F.Mask" "F.Paste")
			(net "RST_SGPIO_RESET_N")
		)
		(pad "B40" smd rect
			(at -5.700014 8.344916 180)
			(size 0.381 1.4478)
			(layers "F.Cu" "F.Mask" "F.Paste")
			(net "IRQ_SGPIO_INTR_N")
		)
		(pad "B41" smd rect
			(at -5.700014 8.945118 180)
			(size 0.381 1.4478)
			(layers "F.Cu" "F.Mask" "F.Paste")
			(net "P3V_BAT_R1")
		)
		(pad "B42" smd rect
			(at -5.700014 9.545066 180)
			(size 0.381 1.4478)
			(layers "F.Cu" "F.Mask" "F.Paste")
			(net "FM_AC_PWR_BTN_N")
		)
		(pad "B43" smd rect
			(at -5.700014 14.454886 180)
			(size 0.381 1.4478)
			(layers "F.Cu" "F.Mask" "F.Paste")
			(net "TP_SPI_2_PLD_CLK")
		)
		(pad "B44" smd rect
			(at -5.700014 15.055088 180)
			(size 0.381 1.4478)
			(layers "F.Cu" "F.Mask" "F.Paste")
			(net "TP_SPI_2_PLD_CS_N")
		)
		(pad "B45" smd rect
			(at -5.700014 15.655036 180)
			(size 0.381 1.4478)
			(layers "F.Cu" "F.Mask" "F.Paste")
			(net "TP_SPI_2_PLD_IO0")
		)
		(pad "B46" smd rect
			(at -5.700014 16.254984 180)
			(size 0.381 1.4478)
			(layers "F.Cu" "F.Mask" "F.Paste")
			(net "TP_SPI_2_PLD_IO1")
		)
		(pad "B47" smd rect
			(at -5.700014 16.854932 180)
			(size 0.381 1.4478)
			(layers "F.Cu" "F.Mask" "F.Paste")
			(net "TP_SPI_2_PLD_IO2")
		)
		(pad "B48" smd rect
			(at -5.700014 17.45488 180)
			(size 0.381 1.4478)
			(layers "F.Cu" "F.Mask" "F.Paste")
			(net "TP_SPI_2_PLD_IO3")
		)
		(pad "B49" smd rect
			(at -5.700014 18.055082 180)
			(size 0.381 1.4478)
			(layers "F.Cu" "F.Mask" "F.Paste")
			(net "GND")
		)
		(pad "B50" smd rect
			(at -5.700014 18.65503 180)
			(size 0.381 1.4478)
			(layers "F.Cu" "F.Mask" "F.Paste")
			(net "USB2_HOST_BMC_B_DP")
		)
		(pad "B51" smd rect
			(at -5.700014 19.254978 180)
			(size 0.381 1.4478)
			(layers "F.Cu" "F.Mask" "F.Paste")
			(net "USB2_HOST_BMC_B_DN")
		)
		(pad "B52" smd rect
			(at -5.700014 19.854926 180)
			(size 0.381 1.4478)
			(layers "F.Cu" "F.Mask" "F.Paste")
			(net "GND")
		)
		(pad "B53" smd rect
			(at -5.700014 20.455128 180)
			(size 0.381 1.4478)
			(layers "F.Cu" "F.Mask" "F.Paste")
			(net "USB2_8_DP")
		)
		(pad "B54" smd rect
			(at -5.700014 21.055076 180)
			(size 0.381 1.4478)
			(layers "F.Cu" "F.Mask" "F.Paste")
			(net "USB2_8_DN")
		)
		(pad "B55" smd rect
			(at -5.700014 21.655024 180)
			(size 0.381 1.4478)
			(layers "F.Cu" "F.Mask" "F.Paste")
			(net "GND")
		)
		(pad "B56" smd rect
			(at -5.700014 22.254972 180)
			(size 0.381 1.4478)
			(layers "F.Cu" "F.Mask" "F.Paste")
			(net "USB2_HUB_2_BUF_EXT_DP")
		)
		(pad "B57" smd rect
			(at -5.700014 22.85492 180)
			(size 0.381 1.4478)
			(layers "F.Cu" "F.Mask" "F.Paste")
			(net "USB2_HUB_2_BUF_EXT_DN")
		)
		(pad "B58" smd rect
			(at -5.700014 23.455122 180)
			(size 0.381 1.4478)
			(layers "F.Cu" "F.Mask" "F.Paste")
			(net "GND")
		)
		(pad "B59" smd rect
			(at -5.700014 24.05507 180)
			(size 0.381 1.4478)
			(layers "F.Cu" "F.Mask" "F.Paste")
			(net "USB3_PCH_TX_BUF_C_DP<4>")
		)
	)
)
